# TIMECARD (Time Appliance Project (Time Card)) — schematic netlist excerpt (pin names and nets, part order shuffled) for the footprints in the layout excerpt that follows; sources: Cadence DE-HDL packaged netlist, KiCad conversion of R4006-B0001-02_R01.brd

R349  RESISTOR  100KOHM 1%  pkg SMC_0402R_H016  page 24 : \1\ = R_FT4232_CHD_RX ; \2\ = XP3R3V_FT4232
R75  RESISTOR  4.7KOHM 1%  pkg SMC_0402R_H016  page 20 : \1\ = XP3R3V_FPGA ; \2\ = BNO080_I2C_SCL

(kicad_pcb
	(version 20260206)
	(generator "pcbnew")
	(generator_version "10.0")
	(general
		(thickness 1.6)
		(legacy_teardrops no)
	)
	(paper "A4")
	(title_block
		(title "timecard-production-celestica-r4006 — R4006-B0001-02_R01.brd")
		(comment 1 "Time Appliance Project (Time Card) / footprints 720-721 of 1113")
	)
	(layers
		(0 "F.Cu" signal "TOP")
		(4 "In1.Cu" signal "L02_GND1")
		(6 "In2.Cu" signal "L03_SIG1")
		(8 "In3.Cu" signal "L04_GND2")
		(10 "In4.Cu" signal "L05_VCC1")
		(12 "In5.Cu" signal "L06_VCC2")
		(14 "In6.Cu" signal "L07_GND3")
		(16 "In7.Cu" signal "L08_SIG2")
		(18 "In8.Cu" signal "L09_GND4")
		(2 "B.Cu" signal "BOTTOM")
		(9 "F.Adhes" user "F.Adhesive")
		(11 "B.Adhes" user "B.Adhesive")
		(13 "F.Paste" user "Package Geometry/Pastemask Top")
		(15 "B.Paste" user "Package Geometry/Pastemask Bottom")
		(5 "F.SilkS" user "Ref Des/Silkscreen Top")
		(7 "B.SilkS" user "Ref Des/Silkscreen Bottom")
		(1 "F.Mask" user "Board Geometry/Soldermask Top")
		(3 "B.Mask" user "Board Geometry/Soldermask Bottom")
		(17 "Dwgs.User" user "User.Drawings")
		(19 "Cmts.User" user "User.Comments")
		(21 "Eco1.User" user "User.Eco1")
		(23 "Eco2.User" user "User.Eco2")
		(25 "Edge.Cuts" user "Board Geometry/Outline")
		(27 "Margin" user)
		(31 "F.CrtYd" user "Package Geometry/Place Bound Top")
		(29 "B.CrtYd" user "Package Geometry/Place Bound Bottom")
		(35 "F.Fab" user "Ref Des/Assembly Top")
		(33 "B.Fab" user "Ref Des/Assembly Bottom")
	)
	(footprint ""
		(layer "B.Cu")
		(at 85.09 -57.277)
		(property "Reference" "R75"
			(at -0.254 -1.10363 0)
			(unlocked yes)
			(layer "B.SilkS")
			(effects
				(font
					(size 0.7874 0.5842)
					(thickness 0.1524)
				)
				(justify mirror)
			)
		)
		(property "Value" "VAL*"
			(at -0.02032 2.13233 0)
			(unlocked yes)
			(layer "B.Fab")
			(hide yes)
			(effects
				(font
					(size 0.7874 0.5842)
					(thickness 0.1524)
				)
				(justify mirror)
			)
		)
		(property "Device Type" "RESISTOR-G155-14701-01,4.7KOHMA"
			(at -0.008382 1.210564 0)
			(unlocked yes)
			(layer "B.Fab")
			(hide yes)
			(effects
				(font
					(size 0.7874 0.5842)
					(thickness 0.1524)
				)
				(justify mirror)
			)
		)
		(property "User Part Number" "PARTNUM*"
			(at -0.02032 4.024884 0)
			(unlocked yes)
			(layer "Cmts.User")
			(hide yes)
			(effects
				(font
					(size 0.7874 0.5842)
					(thickness 0.1524)
				)
				(justify mirror)
			)
		)
		(property "Tolerance" "TOL*"
			(at -0.044704 3.05435 0)
			(unlocked yes)
			(layer "Cmts.User")
			(hide yes)
			(effects
				(font
					(size 0.7874 0.5842)
					(thickness 0.1524)
				)
				(justify mirror)
			)
		)
		(duplicate_pad_numbers_are_jumpers no)
		(fp_line
			(start -1.143 -0.5588)
			(end 1.143 -0.5588)
			(stroke
				(width 0.1)
				(type default)
			)
			(layer "B.SilkS")
		)
		(fp_line
			(start -1.143 0.5588)
			(end -1.143 -0.5588)
			(stroke
				(width 0.1)
				(type default)
			)
			(layer "B.SilkS")
		)
		(fp_line
			(start 1.143 -0.5588)
			(end 1.143 0.5588)
			(stroke
				(width 0.1)
				(type default)
			)
			(layer "B.SilkS")
		)
		(fp_line
			(start 1.143 0.5588)
			(end -1.143 0.5588)
			(stroke
				(width 0.1)
				(type default)
			)
			(layer "B.SilkS")
		)
		(fp_rect
			(start -1.143 -0.5588)
			(end 1.143 0.5588)
			(stroke
				(width 0)
				(type default)
			)
			(fill no)
			(layer "B.CrtYd")
		)
		(fp_line
			(start -0.508 -0.3048)
			(end 0.508 -0.3048)
			(stroke
				(width 0.1)
				(type default)
			)
			(layer "B.Fab")
		)
		(fp_line
			(start -0.508 0.3048)
			(end -0.508 -0.3048)
			(stroke
				(width 0.1)
				(type default)
			)
			(layer "B.Fab")
		)
		(fp_line
			(start 0.508 -0.3048)
			(end 0.508 0.3048)
			(stroke
				(width 0.1)
				(type default)
			)
			(layer "B.Fab")
		)
		(fp_line
			(start 0.508 0.3048)
			(end -0.508 0.3048)
			(stroke
				(width 0.1)
				(type default)
			)
			(layer "B.Fab")
		)
		(pad "1" smd rect
			(at 0.5334 0 180)
			(size 0.7112 0.6096)
			(layers "B.Cu" "B.Mask" "B.Paste")
			(net "XP3R3V_FPGA")
		)
		(pad "2" smd rect
			(at -0.5334 0 180)
			(size 0.7112 0.6096)
			(layers "B.Cu" "B.Mask" "B.Paste")
			(net "BNO080_I2C_SCL")
		)
		(zone
			(layer "B.Cu")
			(hatch none 0.5)
			(connect_pads
				(clearance 0)
			)
			(min_thickness 0.25)
			(keepout
				(tracks allowed)
				(vias not_allowed)
				(pads allowed)
				(copperpour not_allowed)
				(footprints allowed)
			)
			(placement
				(enabled no)
				(sheetname "")
			)
			(fill
				(thermal_gap 0.5)
				(thermal_bridge_width 0.5)
				(island_removal_mode 0)
			)
			(polygon
				(pts
					(xy 85.0138 -57.5818) (xy 85.0138 -56.9722) (xy 85.1662 -56.9722) (xy 85.1662 -57.5818)
				)
			)
		)
	)
	(footprint ""
		(layer "B.Cu")
		(at 34.544 -82.169 180)
		(property "Reference" "R349"
			(at 0.381 2.37363 0)
			(unlocked yes)
			(layer "B.SilkS")
			(effects
				(font
					(size 0.7874 0.5842)
					(thickness 0.1524)
				)
				(justify mirror)
			)
		)
		(property "Value" "VAL*"
			(at -0.02032 2.13233 180)
			(unlocked yes)
			(layer "B.Fab")
			(hide yes)
			(effects
				(font
					(size 0.7874 0.5842)
					(thickness 0.1524)
				)
				(justify mirror)
			)
		)
		(property "Tolerance" "TOL*"
			(at -0.044704 3.05435 180)
			(unlocked yes)
			(layer "Cmts.User")
			(hide yes)
			(effects
				(font
					(size 0.7874 0.5842)
					(thickness 0.1524)
				)
				(justify mirror)
			)
		)
		(property "User Part Number" "PARTNUM*"
			(at -0.02032 4.024884 180)
			(unlocked yes)
			(layer "Cmts.User")
			(hide yes)
			(effects
				(font
					(size 0.7874 0.5842)
					(thickness 0.1524)
				)
				(justify mirror)
			)
		)
		(property "Device Type" "RESISTOR-G155-11003-01,100KOHMA"
			(at -0.008382 1.210564 180)
			(unlocked yes)
			(layer "B.Fab")
			(hide yes)
			(effects
				(font
					(size 0.7874 0.5842)
					(thickness 0.1524)
				)
				(justify mirror)
			)
		)
		(duplicate_pad_numbers_are_jumpers no)
		(fp_line
			(start 1.143 0.5588)
			(end -1.143 0.5588)
			(stroke
				(width 0.1)
				(type default)
			)
			(layer "B.SilkS")
		)
		(fp_line
			(start 1.143 -0.5588)
			(end 1.143 0.5588)
			(stroke
				(width 0.1)
				(type default)
			)
			(layer "B.SilkS")
		)
		(fp_line
			(start -1.143 0.5588)
			(end -1.143 -0.5588)
			(stroke
				(width 0.1)
				(type default)
			)
			(layer "B.SilkS")
		)
		(fp_line
			(start -1.143 -0.5588)
			(end 1.143 -0.5588)
			(stroke
				(width 0.1)
				(type default)
			)
			(layer "B.SilkS")
		)
		(fp_rect
			(start 1.143 0.5588)
			(end -1.143 -0.5588)
			(stroke
				(width 0)
				(type default)
			)
			(fill no)
			(layer "B.CrtYd")
		)
		(fp_line
			(start 0.508 0.3048)
			(end -0.508 0.3048)
			(stroke
				(width 0.1)
				(type default)
			)
			(layer "B.Fab")
		)
		(fp_line
			(start 0.508 -0.3048)
			(end 0.508 0.3048)
			(stroke
				(width 0.1)
				(type default)
			)
			(layer "B.Fab")
		)
		(fp_line
			(start -0.508 0.3048)
			(end -0.508 -0.3048)
			(stroke
				(width 0.1)
				(type default)
			)
			(layer "B.Fab")
		)
		(fp_line
			(start -0.508 -0.3048)
			(end 0.508 -0.3048)
			(stroke
				(width 0.1)
				(type default)
			)
			(layer "B.Fab")
		)
		(pad "1" smd rect
			(at 0.5334 0)
			(size 0.7112 0.6096)
			(layers "B.Cu" "B.Mask" "B.Paste")
			(net "R_FT4232_CHD_RX")
		)
		(pad "2" smd rect
			(at -0.5334 0)
			(size 0.7112 0.6096)
			(layers "B.Cu" "B.Mask" "B.Paste")
			(net "XP3R3V_FT4232")
		)
		(zone
			(layer "B.Cu")
			(hatch none 0.5)
			(connect_pads
				(clearance 0)
			)
			(min_thickness 0.25)
			(keepout
				(tracks allowed)
				(vias not_allowed)
				(pads allowed)
				(copperpour not_allowed)
				(footprints allowed)
			)
			(placement
				(enabled no)
				(sheetname "")
			)
			(fill
				(thermal_gap 0.5)
				(thermal_bridge_width 0.5)
				(island_removal_mode 0)
			)
			(polygon
				(pts
					(xy 34.4678 -82.4738) (xy 34.4678 -81.8642) (xy 34.6202 -81.8642) (xy 34.6202 -82.4738)
				)
			)
		)
		(zone
			(layer "B.Cu")
			(hatch none 0.5)
			(connect_pads
				(clearance 0)
			)
			(min_thickness 0.25)
			(keepout
				(tracks not_allowed)
				(vias allowed)
				(pads allowed)
				(copperpour not_allowed)
				(footprints allowed)
			)
			(placement
				(enabled no)
				(sheetname "")
			)
			(fill
				(thermal_gap 0.5)
				(thermal_bridge_width 0.5)
				(island_removal_mode 0)
			)
			(polygon
				(pts
					(xy 34.4678 -82.4738) (xy 34.4678 -81.8642) (xy 34.6202 -81.8642) (xy 34.6202 -82.4738)
				)
			)
		)
	)
)
